# S9S_MB_2U (Grand Teton) — schematic netlist excerpt (pin names and nets, part order shuffled) for the footprints in the layout excerpt that follows; sources: Cadence DE-HDL packaged netlist, KiCad conversion of 03242023_DA0F0TMBIJ0_F0T_Motherboard_J_brd_V01_OCP.brd

R702  Q_RES  10K 1% EMPTY  pkg 0402LF  page 130 : A = RST_PLD_CPU1_DRAM_GH_N ; B = GND
C1189  Q_CAP  2.2UF 10V 10% X6S  pkg C0402  page 189 : A = P1V05_PCH_AUX ; B = GND
C18  Q_CAP  10UF 16V 10% X6S  pkg C0805  page 87 : A = P12V_S3_AUX_CPU0_NVDIMM ; B = GND

(kicad_pcb
	(version 20260206)
	(generator "pcbnew")
	(generator_version "10.0")
	(general
		(thickness 1.6)
		(legacy_teardrops no)
	)
	(paper "A4")
	(title_block
		(title "03242023_DA0F0TMBIJ0_F0T_Motherboard_J_brd_V01_OCP.brd")
		(comment 1 "Grand Teton / footprints 4549-4551 of 6105")
	)
	(layers
		(0 "F.Cu" signal "TOP")
		(4 "In1.Cu" signal "GND")
		(6 "In2.Cu" signal "IN1")
		(8 "In3.Cu" signal "GND1")
		(10 "In4.Cu" signal "IN2")
		(12 "In5.Cu" signal "GND2")
		(14 "In6.Cu" signal "IN3")
		(16 "In7.Cu" signal "GND3")
		(18 "In8.Cu" signal "VCC")
		(20 "In9.Cu" signal "VCC1")
		(22 "In10.Cu" signal "GND4")
		(24 "In11.Cu" signal "IN4")
		(26 "In12.Cu" signal "GND5")
		(28 "In13.Cu" signal "IN5")
		(30 "In14.Cu" signal "GND6")
		(32 "In15.Cu" signal "IN6")
		(34 "In16.Cu" signal "GND7")
		(2 "B.Cu" signal "BOTTOM")
		(9 "F.Adhes" user "F.Adhesive")
		(11 "B.Adhes" user "B.Adhesive")
		(13 "F.Paste" user "Package Geometry/Pastemask Top")
		(15 "B.Paste" user "Package Geometry/Pastemask Bottom")
		(5 "F.SilkS" user "Ref Des/Silkscreen Top")
		(7 "B.SilkS" user "Ref Des/Silkscreen Bottom")
		(1 "F.Mask" user "Board Geometry/Soldermask Top")
		(3 "B.Mask" user "Board Geometry/Soldermask Bottom")
		(17 "Dwgs.User" user "User.Drawings")
		(19 "Cmts.User" user "User.Comments")
		(21 "Eco1.User" user "User.Eco1")
		(23 "Eco2.User" user "User.Eco2")
		(25 "Edge.Cuts" user "Board Geometry/Outline")
		(27 "Margin" user)
		(31 "F.CrtYd" user "Package Geometry/Place Bound Top")
		(29 "B.CrtYd" user "Package Geometry/Place Bound Bottom")
		(35 "F.Fab" user "Ref Des/Assembly Top")
		(33 "B.Fab" user "Ref Des/Assembly Bottom")
	)
	(footprint ""
		(layer "B.Cu")
		(at 334.59674 -49.022508)
		(property "Reference" "C1189"
			(at 0 0 0)
			(layer "B.SilkS")
			(hide yes)
			(effects
				(font
					(size 1.27 1.27)
				)
				(justify mirror)
			)
		)
		(property "Value" ""
			(at 0 0 0)
			(layer "B.Fab")
			(effects
				(font
					(size 1.27 1.27)
				)
				(justify mirror)
			)
		)
		(duplicate_pad_numbers_are_jumpers no)
		(fp_line
			(start -0.7874 -0.4064)
			(end -0.7874 0.4064)
			(stroke
				(width 0.1524)
				(type default)
			)
			(layer "B.SilkS")
		)
		(fp_line
			(start -0.7874 0.4064)
			(end 0.7874 0.4064)
			(stroke
				(width 0.1524)
				(type default)
			)
			(layer "B.SilkS")
		)
		(fp_line
			(start 0.7874 -0.4064)
			(end -0.7874 -0.4064)
			(stroke
				(width 0.1524)
				(type default)
			)
			(layer "B.SilkS")
		)
		(fp_line
			(start 0.7874 0.4064)
			(end 0.7874 -0.4064)
			(stroke
				(width 0.1524)
				(type default)
			)
			(layer "B.SilkS")
		)
		(fp_line
			(start -0.67945 -0.3048)
			(end -0.67945 0.3048)
			(stroke
				(width 0.1)
				(type default)
			)
			(layer "B.Fab")
		)
		(fp_line
			(start -0.67945 0.3048)
			(end -0.120396 0.3048)
			(stroke
				(width 0.1)
				(type default)
			)
			(layer "B.Fab")
		)
		(fp_line
			(start -0.12065 -0.3048)
			(end -0.67945 -0.3048)
			(stroke
				(width 0.1)
				(type default)
			)
			(layer "B.Fab")
		)
		(fp_line
			(start -0.12065 -0.2794)
			(end -0.12065 -0.3048)
			(stroke
				(width 0.1)
				(type default)
			)
			(layer "B.Fab")
		)
		(fp_line
			(start -0.120396 0.2794)
			(end 0.12065 0.2794)
			(stroke
				(width 0.1)
				(type default)
			)
			(layer "B.Fab")
		)
		(fp_line
			(start -0.120396 0.3048)
			(end -0.120396 0.2794)
			(stroke
				(width 0.1)
				(type default)
			)
			(layer "B.Fab")
		)
		(fp_line
			(start 0.12065 -0.305054)
			(end 0.12065 -0.2794)
			(stroke
				(width 0.1)
				(type default)
			)
			(layer "B.Fab")
		)
		(fp_line
			(start 0.12065 -0.2794)
			(end -0.12065 -0.2794)
			(stroke
				(width 0.1)
				(type default)
			)
			(layer "B.Fab")
		)
		(fp_line
			(start 0.12065 0.2794)
			(end 0.12065 0.3048)
			(stroke
				(width 0.1)
				(type default)
			)
			(layer "B.Fab")
		)
		(fp_line
			(start 0.12065 0.3048)
			(end 0.67945 0.3048)
			(stroke
				(width 0.1)
				(type default)
			)
			(layer "B.Fab")
		)
		(fp_line
			(start 0.67945 -0.305054)
			(end 0.12065 -0.305054)
			(stroke
				(width 0.1)
				(type default)
			)
			(layer "B.Fab")
		)
		(fp_line
			(start 0.67945 0.3048)
			(end 0.67945 -0.305054)
			(stroke
				(width 0.1)
				(type default)
			)
			(layer "B.Fab")
		)
		(pad "1" smd circle
			(at 0.40005 0 180)
			(size 0 0)
			(layers "B.Cu" "B.Mask" "B.Paste")
			(net "P1V05_PCH_AUX")
		)
		(pad "2" smd circle
			(at -0.40005 0 180)
			(size 0 0)
			(layers "B.Cu" "B.Mask" "B.Paste")
			(net "GND")
		)
	)
	(footprint ""
		(layer "B.Cu")
		(at 192.280286 -193.615056 -90)
		(property "Reference" "R702"
			(at 0 0 90)
			(layer "B.SilkS")
			(hide yes)
			(effects
				(font
					(size 1.27 1.27)
				)
				(justify mirror)
			)
		)
		(property "Value" ""
			(at 0 0 90)
			(layer "B.Fab")
			(effects
				(font
					(size 1.27 1.27)
				)
				(justify mirror)
			)
		)
		(duplicate_pad_numbers_are_jumpers no)
		(fp_line
			(start -0.7874 0.4064)
			(end 0.7874 0.4064)
			(stroke
				(width 0.1524)
				(type default)
			)
			(layer "B.SilkS")
		)
		(fp_line
			(start 0.7874 0.4064)
			(end 0.7874 -0.4064)
			(stroke
				(width 0.1524)
				(type default)
			)
			(layer "B.SilkS")
		)
		(fp_line
			(start -0.7874 -0.4064)
			(end -0.7874 0.4064)
			(stroke
				(width 0.1524)
				(type default)
			)
			(layer "B.SilkS")
		)
		(fp_line
			(start 0.7874 -0.4064)
			(end -0.7874 -0.4064)
			(stroke
				(width 0.1524)
				(type default)
			)
			(layer "B.SilkS")
		)
		(fp_line
			(start -0.67945 0.3048)
			(end -0.120396 0.3048)
			(stroke
				(width 0.1)
				(type default)
			)
			(layer "B.Fab")
		)
		(fp_line
			(start -0.120396 0.3048)
			(end -0.120396 0.2794)
			(stroke
				(width 0.1)
				(type default)
			)
			(layer "B.Fab")
		)
		(fp_line
			(start 0.12065 0.3048)
			(end 0.67945 0.3048)
			(stroke
				(width 0.1)
				(type default)
			)
			(layer "B.Fab")
		)
		(fp_line
			(start 0.67945 0.3048)
			(end 0.67945 -0.305054)
			(stroke
				(width 0.1)
				(type default)
			)
			(layer "B.Fab")
		)
		(fp_line
			(start -0.120396 0.2794)
			(end 0.12065 0.2794)
			(stroke
				(width 0.1)
				(type default)
			)
			(layer "B.Fab")
		)
		(fp_line
			(start 0.12065 0.2794)
			(end 0.12065 0.3048)
			(stroke
				(width 0.1)
				(type default)
			)
			(layer "B.Fab")
		)
		(fp_line
			(start -0.12065 -0.2794)
			(end -0.12065 -0.3048)
			(stroke
				(width 0.1)
				(type default)
			)
			(layer "B.Fab")
		)
		(fp_line
			(start 0.12065 -0.2794)
			(end -0.12065 -0.2794)
			(stroke
				(width 0.1)
				(type default)
			)
			(layer "B.Fab")
		)
		(fp_line
			(start -0.67945 -0.3048)
			(end -0.67945 0.3048)
			(stroke
				(width 0.1)
				(type default)
			)
			(layer "B.Fab")
		)
		(fp_line
			(start -0.12065 -0.3048)
			(end -0.67945 -0.3048)
			(stroke
				(width 0.1)
				(type default)
			)
			(layer "B.Fab")
		)
		(fp_line
			(start 0.12065 -0.305054)
			(end 0.12065 -0.2794)
			(stroke
				(width 0.1)
				(type default)
			)
			(layer "B.Fab")
		)
		(fp_line
			(start 0.67945 -0.305054)
			(end 0.12065 -0.305054)
			(stroke
				(width 0.1)
				(type default)
			)
			(layer "B.Fab")
		)
		(pad "1" smd circle
			(at 0.40005 0 90)
			(size 0 0)
			(layers "B.Cu" "B.Mask" "B.Paste")
			(net "RST_PLD_CPU1_DRAM_GH_N")
		)
		(pad "2" smd circle
			(at -0.40005 0 90)
			(size 0 0)
			(layers "B.Cu" "B.Mask" "B.Paste")
			(net "GND")
		)
	)
	(footprint ""
		(layer "B.Cu")
		(at 282.788614 -321.549776 -90)
		(property "Reference" "C18"
			(at 0 0 90)
			(layer "B.SilkS")
			(hide yes)
			(effects
				(font
					(size 1.27 1.27)
				)
				(justify mirror)
			)
		)
		(property "Value" ""
			(at 0 0 90)
			(layer "B.Fab")
			(effects
				(font
					(size 1.27 1.27)
				)
				(justify mirror)
			)
		)
		(duplicate_pad_numbers_are_jumpers no)
		(fp_line
			(start -1.524 0.762)
			(end 1.524 0.762)
			(stroke
				(width 0.1524)
				(type default)
			)
			(layer "B.SilkS")
		)
		(fp_line
			(start 1.524 0.762)
			(end 1.524 -0.762)
			(stroke
				(width 0.1524)
				(type default)
			)
			(layer "B.SilkS")
		)
		(fp_line
			(start -1.524 -0.762)
			(end -1.524 0.762)
			(stroke
				(width 0.1524)
				(type default)
			)
			(layer "B.SilkS")
		)
		(fp_line
			(start 1.524 -0.762)
			(end -1.524 -0.762)
			(stroke
				(width 0.1524)
				(type default)
			)
			(layer "B.SilkS")
		)
		(fp_line
			(start -1.1049 0.724916)
			(end -1.1049 -0.724916)
			(stroke
				(width 0.1)
				(type default)
			)
			(layer "B.Fab")
		)
		(fp_line
			(start 1.1049 0.724916)
			(end -1.1049 0.724916)
			(stroke
				(width 0.1)
				(type default)
			)
			(layer "B.Fab")
		)
		(fp_line
			(start -1.1049 -0.724916)
			(end 1.1049 -0.724916)
			(stroke
				(width 0.1)
				(type default)
			)
			(layer "B.Fab")
		)
		(fp_line
			(start 1.1049 -0.724916)
			(end 1.1049 0.724916)
			(stroke
				(width 0.1)
				(type default)
			)
			(layer "B.Fab")
		)
		(pad "1" smd rect
			(at 0.889 0 270)
			(size 1.016 1.27)
			(layers "B.Cu" "B.Mask" "B.Paste")
			(net "P12V_S3_AUX_CPU0_NVDIMM")
		)
		(pad "2" smd rect
			(at -0.889 0 270)
			(size 1.016 1.27)
			(layers "B.Cu" "B.Mask" "B.Paste")
			(net "GND")
		)
	)
)
